(kicad_pcb
	(version 20260206)
	(generator "pcbnew")
	(generator_version "10.0")
	(general
		(thickness 1.6)
		(legacy_teardrops no)
	)
	(paper "A4")
	(title_block
		(title "01162023_DA0F0TEBIF0_F0T_Expander_BD_F_brd_V02_OCP.brd")
		(comment 1 "Grand Teton / footprints 5149-5154 of 9728")
	)
	(layers
		(0 "F.Cu" signal "TOP")
		(4 "In1.Cu" signal "GND")
		(6 "In2.Cu" signal "VCC")
		(8 "In3.Cu" signal "VCC1")
		(10 "In4.Cu" signal "GND1")
		(12 "In5.Cu" signal "IN1")
		(14 "In6.Cu" signal "GND2")
		(16 "In7.Cu" signal "IN2")
		(18 "In8.Cu" signal "GND3")
		(20 "In9.Cu" signal "IN3")
		(22 "In10.Cu" signal "GND4")
		(24 "In11.Cu" signal "IN4")
		(26 "In12.Cu" signal "GND5")
		(28 "In13.Cu" signal "IN5")
		(30 "In14.Cu" signal "GND6")
		(32 "In15.Cu" signal "IN6")
		(34 "In16.Cu" signal "GND7")
		(2 "B.Cu" signal "BOTTOM")
		(9 "F.Adhes" user "F.Adhesive")
		(11 "B.Adhes" user "B.Adhesive")
		(13 "F.Paste" user "Package Geometry/Pastemask Top")
		(15 "B.Paste" user "Package Geometry/Pastemask Bottom")
		(5 "F.SilkS" user "Ref Des/Silkscreen Top")
		(7 "B.SilkS" user "Ref Des/Silkscreen Bottom")
		(1 "F.Mask" user "Board Geometry/Soldermask Top")
		(3 "B.Mask" user "Board Geometry/Soldermask Bottom")
		(17 "Dwgs.User" user "User.Drawings")
		(19 "Cmts.User" user "User.Comments")
		(21 "Eco1.User" user "User.Eco1")
		(23 "Eco2.User" user "User.Eco2")
		(25 "Edge.Cuts" user "Board Geometry/Outline")
		(27 "Margin" user)
		(31 "F.CrtYd" user "Package Geometry/Place Bound Top")
		(29 "B.CrtYd" user "Package Geometry/Place Bound Bottom")
		(35 "F.Fab" user "Ref Des/Assembly Top")
		(33 "B.Fab" user "Ref Des/Assembly Bottom")
	)
	(footprint ""
		(layer "F.Cu")
		(at 284.467808 -51.019456)
		(property "Reference" "PC422"
			(at 0 0 0)
			(layer "F.SilkS")
			(hide yes)
			(effects
				(font
					(size 1.27 1.27)
				)
			)
		)
		(property "Value" ""
			(at 0 0 0)
			(layer "F.Fab")
			(effects
				(font
					(size 1.27 1.27)
				)
			)
		)
		(duplicate_pad_numbers_are_jumpers no)
		(fp_line
			(start -0.7874 -0.4064)
			(end 0.7874 -0.4064)
			(stroke
				(width 0.1524)
				(type default)
			)
			(layer "F.SilkS")
		)
		(fp_line
			(start -0.7874 0.4064)
			(end -0.7874 -0.4064)
			(stroke
				(width 0.1524)
				(type default)
			)
			(layer "F.SilkS")
		)
		(fp_line
			(start 0.7874 -0.4064)
			(end 0.7874 0.4064)
			(stroke
				(width 0.1524)
				(type default)
			)
			(layer "F.SilkS")
		)
		(fp_line
			(start 0.7874 0.4064)
			(end -0.7874 0.4064)
			(stroke
				(width 0.1524)
				(type default)
			)
			(layer "F.SilkS")
		)
		(fp_line
			(start -0.67945 -0.305054)
			(end -0.12065 -0.305054)
			(stroke
				(width 0.1)
				(type default)
			)
			(layer "F.Fab")
		)
		(fp_line
			(start -0.67945 0.3048)
			(end -0.67945 -0.305054)
			(stroke
				(width 0.1)
				(type default)
			)
			(layer "F.Fab")
		)
		(fp_line
			(start -0.12065 -0.305054)
			(end -0.12065 -0.2794)
			(stroke
				(width 0.1)
				(type default)
			)
			(layer "F.Fab")
		)
		(fp_line
			(start -0.12065 -0.2794)
			(end 0.12065 -0.2794)
			(stroke
				(width 0.1)
				(type default)
			)
			(layer "F.Fab")
		)
		(fp_line
			(start -0.12065 0.2794)
			(end -0.12065 0.3048)
			(stroke
				(width 0.1)
				(type default)
			)
			(layer "F.Fab")
		)
		(fp_line
			(start -0.12065 0.3048)
			(end -0.67945 0.3048)
			(stroke
				(width 0.1)
				(type default)
			)
			(layer "F.Fab")
		)
		(fp_line
			(start 0.120396 0.2794)
			(end -0.12065 0.2794)
			(stroke
				(width 0.1)
				(type default)
			)
			(layer "F.Fab")
		)
		(fp_line
			(start 0.120396 0.3048)
			(end 0.120396 0.2794)
			(stroke
				(width 0.1)
				(type default)
			)
			(layer "F.Fab")
		)
		(fp_line
			(start 0.12065 -0.3048)
			(end 0.67945 -0.3048)
			(stroke
				(width 0.1)
				(type default)
			)
			(layer "F.Fab")
		)
		(fp_line
			(start 0.12065 -0.2794)
			(end 0.12065 -0.3048)
			(stroke
				(width 0.1)
				(type default)
			)
			(layer "F.Fab")
		)
		(fp_line
			(start 0.67945 -0.3048)
			(end 0.67945 0.3048)
			(stroke
				(width 0.1)
				(type default)
			)
			(layer "F.Fab")
		)
		(fp_line
			(start 0.67945 0.3048)
			(end 0.120396 0.3048)
			(stroke
				(width 0.1)
				(type default)
			)
			(layer "F.Fab")
		)
		(pad "1" smd circle
			(at -0.40005 0)
			(size 0 0)
			(layers "F.Cu" "F.Mask" "F.Paste")
			(net "P12V_SSD9_SS")
		)
		(pad "2" smd circle
			(at 0.40005 0)
			(size 0 0)
			(layers "F.Cu" "F.Mask" "F.Paste")
			(net "GND")
		)
	)
	(footprint ""
		(layer "F.Cu")
		(at 404.114 -86.255606 180)
		(property "Reference" "U421"
			(at 1.3716 -2.284476 0)
			(unlocked yes)
			(layer "F.SilkS")
			(effects
				(font
					(size 0.7874 0.5842)
					(thickness 0.1524)
				)
				(justify left)
			)
		)
		(property "Value" ""
			(at 0 0 180)
			(layer "F.Fab")
			(effects
				(font
					(size 1.27 1.27)
				)
			)
		)
		(duplicate_pad_numbers_are_jumpers no)
		(fp_line
			(start 1.463548 1.549908)
			(end -1.463548 1.549908)
			(stroke
				(width 0.1524)
				(type default)
			)
			(layer "F.SilkS")
		)
		(fp_line
			(start 1.463548 -1.549908)
			(end 1.463548 1.549908)
			(stroke
				(width 0.1524)
				(type default)
			)
			(layer "F.SilkS")
		)
		(fp_line
			(start 0.762 -1.549908)
			(end 1.463548 -1.549908)
			(stroke
				(width 0.1524)
				(type default)
			)
			(layer "F.SilkS")
		)
		(fp_line
			(start 0 -0.762)
			(end 0.762 -1.549908)
			(stroke
				(width 0.1524)
				(type default)
			)
			(layer "F.SilkS")
		)
		(fp_line
			(start -0.787908 -1.549908)
			(end 0 -0.762)
			(stroke
				(width 0.1524)
				(type default)
			)
			(layer "F.SilkS")
		)
		(fp_line
			(start -1.463548 1.549908)
			(end -1.463548 -1.549908)
			(stroke
				(width 0.1524)
				(type default)
			)
			(layer "F.SilkS")
		)
		(fp_line
			(start -1.463548 -1.549908)
			(end -0.787908 -1.549908)
			(stroke
				(width 0.1524)
				(type default)
			)
			(layer "F.SilkS")
		)
		(fp_poly
			(pts
				(xy -3.4798 -1.359916) (xy -2.86004 -1.050036) (xy -3.4798 -0.740156)
			)
			(stroke
				(width 0)
				(type default)
			)
			(fill yes)
			(layer "F.SilkS")
		)
		(fp_line
			(start 1.549908 1.549908)
			(end -1.549908 1.549908)
			(stroke
				(width 0.1)
				(type default)
			)
			(layer "F.Fab")
		)
		(fp_line
			(start 1.549908 -1.549908)
			(end 1.549908 1.549908)
			(stroke
				(width 0.1)
				(type default)
			)
			(layer "F.Fab")
		)
		(fp_line
			(start -1.549908 1.549908)
			(end -1.549908 -1.549908)
			(stroke
				(width 0.1)
				(type default)
			)
			(layer "F.Fab")
		)
		(fp_line
			(start -1.549908 -1.549908)
			(end 1.549908 -1.549908)
			(stroke
				(width 0.1)
				(type default)
			)
			(layer "F.Fab")
		)
		(fp_poly
			(pts
				(xy -3.4798 -1.359916) (xy -2.86004 -1.050036) (xy -3.4798 -0.740156)
			)
			(stroke
				(width 0)
				(type default)
			)
			(fill yes)
			(layer "F.Fab")
		)
		(pad "1" smd rect
			(at -2.175002 -1.050036 270)
			(size 0.6096 1.1684)
			(layers "F.Cu" "F.Mask" "F.Paste")
			(net "P3V3")
		)
		(pad "2" smd rect
			(at -2.175002 -0.32512 270)
			(size 0.4318 1.1684)
			(layers "F.Cu" "F.Mask" "F.Paste")
			(net "SMB_CLK_ISO_SCL")
		)
		(pad "3" smd rect
			(at -2.175002 0.32512 270)
			(size 0.4318 1.1684)
			(layers "F.Cu" "F.Mask" "F.Paste")
			(net "SMB_CLK_ISO_SDA")
		)
		(pad "4" smd rect
			(at -2.175002 1.050036 270)
			(size 0.6096 1.1684)
			(layers "F.Cu" "F.Mask" "F.Paste")
			(net "GND")
		)
		(pad "5" smd rect
			(at 2.175002 1.050036 270)
			(size 0.6096 1.1684)
			(layers "F.Cu" "F.Mask" "F.Paste")
			(net "CLK_ISO_EN")
		)
		(pad "6" smd rect
			(at 2.175002 0.32512 270)
			(size 0.4318 1.1684)
			(layers "F.Cu" "F.Mask" "F.Paste")
			(net "SMB_BIC_I2C6_MUX_CLK_R_SDA")
		)
		(pad "7" smd rect
			(at 2.175002 -0.32512 270)
			(size 0.4318 1.1684)
			(layers "F.Cu" "F.Mask" "F.Paste")
			(net "SMB_BIC_I2C6_MUX_CLK_R_SCL")
		)
		(pad "8" smd rect
			(at 2.175002 -1.050036 270)
			(size 0.6096 1.1684)
			(layers "F.Cu" "F.Mask" "F.Paste")
			(net "P3V3_AUX")
		)
	)
	(footprint ""
		(layer "F.Cu")
		(at 70.63867 -22.867366 90)
		(property "Reference" "C3892"
			(at 0 0 90)
			(layer "F.SilkS")
			(hide yes)
			(effects
				(font
					(size 1.27 1.27)
				)
			)
		)
		(property "Value" ""
			(at 0 0 90)
			(layer "F.Fab")
			(effects
				(font
					(size 1.27 1.27)
				)
			)
		)
		(duplicate_pad_numbers_are_jumpers no)
		(fp_line
			(start 0.7874 -0.4064)
			(end 0.7874 0.4064)
			(stroke
				(width 0.1524)
				(type default)
			)
			(layer "F.SilkS")
		)
		(fp_line
			(start -0.7874 -0.4064)
			(end 0.7874 -0.4064)
			(stroke
				(width 0.1524)
				(type default)
			)
			(layer "F.SilkS")
		)
		(fp_line
			(start 0.7874 0.4064)
			(end -0.7874 0.4064)
			(stroke
				(width 0.1524)
				(type default)
			)
			(layer "F.SilkS")
		)
		(fp_line
			(start -0.7874 0.4064)
			(end -0.7874 -0.4064)
			(stroke
				(width 0.1524)
				(type default)
			)
			(layer "F.SilkS")
		)
		(fp_line
			(start -0.12065 -0.305054)
			(end -0.12065 -0.2794)
			(stroke
				(width 0.1)
				(type default)
			)
			(layer "F.Fab")
		)
		(fp_line
			(start -0.67945 -0.305054)
			(end -0.12065 -0.305054)
			(stroke
				(width 0.1)
				(type default)
			)
			(layer "F.Fab")
		)
		(fp_line
			(start 0.67945 -0.3048)
			(end 0.67945 0.3048)
			(stroke
				(width 0.1)
				(type default)
			)
			(layer "F.Fab")
		)
		(fp_line
			(start 0.12065 -0.3048)
			(end 0.67945 -0.3048)
			(stroke
				(width 0.1)
				(type default)
			)
			(layer "F.Fab")
		)
		(fp_line
			(start 0.12065 -0.2794)
			(end 0.12065 -0.3048)
			(stroke
				(width 0.1)
				(type default)
			)
			(layer "F.Fab")
		)
		(fp_line
			(start -0.12065 -0.2794)
			(end 0.12065 -0.2794)
			(stroke
				(width 0.1)
				(type default)
			)
			(layer "F.Fab")
		)
		(fp_line
			(start 0.120396 0.2794)
			(end -0.12065 0.2794)
			(stroke
				(width 0.1)
				(type default)
			)
			(layer "F.Fab")
		)
		(fp_line
			(start -0.12065 0.2794)
			(end -0.12065 0.3048)
			(stroke
				(width 0.1)
				(type default)
			)
			(layer "F.Fab")
		)
		(fp_line
			(start 0.67945 0.3048)
			(end 0.120396 0.3048)
			(stroke
				(width 0.1)
				(type default)
			)
			(layer "F.Fab")
		)
		(fp_line
			(start 0.120396 0.3048)
			(end 0.120396 0.2794)
			(stroke
				(width 0.1)
				(type default)
			)
			(layer "F.Fab")
		)
		(fp_line
			(start -0.12065 0.3048)
			(end -0.67945 0.3048)
			(stroke
				(width 0.1)
				(type default)
			)
			(layer "F.Fab")
		)
		(fp_line
			(start -0.67945 0.3048)
			(end -0.67945 -0.305054)
			(stroke
				(width 0.1)
				(type default)
			)
			(layer "F.Fab")
		)
		(pad "1" smd circle
			(at -0.40005 0 90)
			(size 0 0)
			(layers "F.Cu" "F.Mask" "F.Paste")
			(net "P12V_SSD2")
		)
		(pad "2" smd circle
			(at 0.40005 0 90)
			(size 0 0)
			(layers "F.Cu" "F.Mask" "F.Paste")
			(net "GND")
		)
	)
	(footprint ""
		(layer "F.Cu")
		(at 258.778502 -308.611524 45)
		(property "Reference" "R4362"
			(at 0 0 45)
			(layer "F.SilkS")
			(hide yes)
			(effects
				(font
					(size 1.27 1.27)
				)
			)
		)
		(property "Value" ""
			(at 0 0 45)
			(layer "F.Fab")
			(effects
				(font
					(size 1.27 1.27)
				)
			)
		)
		(duplicate_pad_numbers_are_jumpers no)
		(fp_line
			(start -0.787389 -0.406267)
			(end 0.787389 -0.406267)
			(stroke
				(width 0.1524)
				(type default)
			)
			(layer "F.SilkS")
		)
		(fp_line
			(start -0.787389 0.406267)
			(end -0.787389 -0.406267)
			(stroke
				(width 0.1524)
				(type default)
			)
			(layer "F.SilkS")
		)
		(fp_line
			(start 0.787389 -0.406267)
			(end 0.787389 0.406267)
			(stroke
				(width 0.1524)
				(type default)
			)
			(layer "F.SilkS")
		)
		(fp_line
			(start 0.787389 0.406267)
			(end -0.787389 0.406267)
			(stroke
				(width 0.1524)
				(type default)
			)
			(layer "F.SilkS")
		)
		(fp_line
			(start -0.679446 -0.305149)
			(end -0.120695 -0.304969)
			(stroke
				(width 0.1)
				(type default)
			)
			(layer "F.Fab")
		)
		(fp_line
			(start -0.120695 -0.304969)
			(end -0.120695 -0.279466)
			(stroke
				(width 0.1)
				(type default)
			)
			(layer "F.Fab")
		)
		(fp_line
			(start -0.120695 -0.279466)
			(end 0.120695 -0.279466)
			(stroke
				(width 0.1)
				(type default)
			)
			(layer "F.Fab")
		)
		(fp_line
			(start -0.679446 0.30479)
			(end -0.679446 -0.305149)
			(stroke
				(width 0.1)
				(type default)
			)
			(layer "F.Fab")
		)
		(fp_line
			(start 0.120515 -0.30479)
			(end 0.679446 -0.30479)
			(stroke
				(width 0.1)
				(type default)
			)
			(layer "F.Fab")
		)
		(fp_line
			(start 0.120695 -0.279466)
			(end 0.120515 -0.30479)
			(stroke
				(width 0.1)
				(type default)
			)
			(layer "F.Fab")
		)
		(fp_line
			(start -0.120695 0.279466)
			(end -0.120515 0.30479)
			(stroke
				(width 0.1)
				(type default)
			)
			(layer "F.Fab")
		)
		(fp_line
			(start -0.120515 0.30479)
			(end -0.679446 0.30479)
			(stroke
				(width 0.1)
				(type default)
			)
			(layer "F.Fab")
		)
		(fp_line
			(start 0.679446 -0.30479)
			(end 0.679446 0.30479)
			(stroke
				(width 0.1)
				(type default)
			)
			(layer "F.Fab")
		)
		(fp_line
			(start 0.120335 0.279466)
			(end -0.120695 0.279466)
			(stroke
				(width 0.1)
				(type default)
			)
			(layer "F.Fab")
		)
		(fp_line
			(start 0.120515 0.30479)
			(end 0.120335 0.279466)
			(stroke
				(width 0.1)
				(type default)
			)
			(layer "F.Fab")
		)
		(fp_line
			(start 0.679446 0.30479)
			(end 0.120515 0.30479)
			(stroke
				(width 0.1)
				(type default)
			)
			(layer "F.Fab")
		)
		(pad "1" smd circle
			(at -0.40005 0 45)
			(size 0 0)
			(layers "F.Cu" "F.Mask" "F.Paste")
			(net "P1V8_PEX")
		)
		(pad "2" smd circle
			(at 0.40005 0 45)
			(size 0 0)
			(layers "F.Cu" "F.Mask" "F.Paste")
			(net "IRQ_PEX2_CLKREQ_INT_N")
		)
	)
	(footprint ""
		(layer "F.Cu")
		(at 376.305572 -258.511548 -90)
		(property "Reference" "C3596"
			(at 0 0 270)
			(layer "F.SilkS")
			(hide yes)
			(effects
				(font
					(size 1.27 1.27)
				)
			)
		)
		(property "Value" ""
			(at 0 0 270)
			(layer "F.Fab")
			(effects
				(font
					(size 1.27 1.27)
				)
			)
		)
		(duplicate_pad_numbers_are_jumpers no)
		(fp_line
			(start -1.2954 0.5842)
			(end -1.2954 -0.5842)
			(stroke
				(width 0.1524)
				(type default)
			)
			(layer "F.SilkS")
		)
		(fp_line
			(start 1.2954 0.5842)
			(end -1.2954 0.5842)
			(stroke
				(width 0.1524)
				(type default)
			)
			(layer "F.SilkS")
		)
		(fp_line
			(start -1.2954 -0.5842)
			(end 1.2954 -0.5842)
			(stroke
				(width 0.1524)
				(type default)
			)
			(layer "F.SilkS")
		)
		(fp_line
			(start 1.2954 -0.5842)
			(end 1.2954 0.5842)
			(stroke
				(width 0.1524)
				(type default)
			)
			(layer "F.SilkS")
		)
		(fp_line
			(start -0.8636 0.4572)
			(end -0.8636 0.4064)
			(stroke
				(width 0.1)
				(type default)
			)
			(layer "F.Fab")
		)
		(fp_line
			(start 0.8636 0.4572)
			(end -0.8636 0.4572)
			(stroke
				(width 0.1)
				(type default)
			)
			(layer "F.Fab")
		)
		(fp_line
			(start -1.1938 0.4064)
			(end -1.1938 -0.4064)
			(stroke
				(width 0.1)
				(type default)
			)
			(layer "F.Fab")
		)
		(fp_line
			(start -0.8636 0.4064)
			(end -1.1938 0.4064)
			(stroke
				(width 0.1)
				(type default)
			)
			(layer "F.Fab")
		)
		(fp_line
			(start 0.8636 0.4064)
			(end 0.8636 0.4572)
			(stroke
				(width 0.1)
				(type default)
			)
			(layer "F.Fab")
		)
		(fp_line
			(start 1.1938 0.4064)
			(end 0.8636 0.4064)
			(stroke
				(width 0.1)
				(type default)
			)
			(layer "F.Fab")
		)
		(fp_line
			(start -1.1938 -0.4064)
			(end -0.8636 -0.4064)
			(stroke
				(width 0.1)
				(type default)
			)
			(layer "F.Fab")
		)
		(fp_line
			(start -0.8636 -0.4064)
			(end -0.8636 -0.4572)
			(stroke
				(width 0.1)
				(type default)
			)
			(layer "F.Fab")
		)
		(fp_line
			(start 0.8636 -0.4064)
			(end 1.1938 -0.4064)
			(stroke
				(width 0.1)
				(type default)
			)
			(layer "F.Fab")
		)
		(fp_line
			(start 1.1938 -0.4064)
			(end 1.1938 0.4064)
			(stroke
				(width 0.1)
				(type default)
			)
			(layer "F.Fab")
		)
		(fp_line
			(start -0.8636 -0.4572)
			(end 0.8636 -0.4572)
			(stroke
				(width 0.1)
				(type default)
			)
			(layer "F.Fab")
		)
		(fp_line
			(start 0.8636 -0.4572)
			(end 0.8636 -0.4064)
			(stroke
				(width 0.1)
				(type default)
			)
			(layer "F.Fab")
		)
		(pad "1" smd rect
			(at -0.7366 0 180)
			(size 0.7112 0.8128)
			(layers "F.Cu" "F.Mask" "F.Paste")
			(net "P1V8_VDDA_PEX3_R")
		)
		(pad "2" smd rect
			(at 0.7366 0 180)
			(size 0.7112 0.8128)
			(layers "F.Cu" "F.Mask" "F.Paste")
			(net "GND")
		)
	)
	(footprint ""
		(layer "F.Cu")
		(at 229.48265 -309.555642)
		(property "Reference" "PC240"
			(at 0 0 0)
			(layer "F.SilkS")
			(hide yes)
			(effects
				(font
					(size 1.27 1.27)
				)
			)
		)
		(property "Value" ""
			(at 0 0 0)
			(layer "F.Fab")
			(effects
				(font
					(size 1.27 1.27)
				)
			)
		)
		(duplicate_pad_numbers_are_jumpers no)
		(fp_line
			(start -0.7874 -0.4064)
			(end 0.7874 -0.4064)
			(stroke
				(width 0.1524)
				(type default)
			)
			(layer "F.SilkS")
		)
		(fp_line
			(start -0.7874 0.4064)
			(end -0.7874 -0.4064)
			(stroke
				(width 0.1524)
				(type default)
			)
			(layer "F.SilkS")
		)
		(fp_line
			(start 0.7874 -0.4064)
			(end 0.7874 0.4064)
			(stroke
				(width 0.1524)
				(type default)
			)
			(layer "F.SilkS")
		)
		(fp_line
			(start 0.7874 0.4064)
			(end -0.7874 0.4064)
			(stroke
				(width 0.1524)
				(type default)
			)
			(layer "F.SilkS")
		)
		(fp_line
			(start -0.67945 -0.305054)
			(end -0.12065 -0.305054)
			(stroke
				(width 0.1)
				(type default)
			)
			(layer "F.Fab")
		)
		(fp_line
			(start -0.67945 0.3048)
			(end -0.67945 -0.305054)
			(stroke
				(width 0.1)
				(type default)
			)
			(layer "F.Fab")
		)
		(fp_line
			(start -0.12065 -0.305054)
			(end -0.12065 -0.2794)
			(stroke
				(width 0.1)
				(type default)
			)
			(layer "F.Fab")
		)
		(fp_line
			(start -0.12065 -0.2794)
			(end 0.12065 -0.2794)
			(stroke
				(width 0.1)
				(type default)
			)
			(layer "F.Fab")
		)
		(fp_line
			(start -0.12065 0.2794)
			(end -0.12065 0.3048)
			(stroke
				(width 0.1)
				(type default)
			)
			(layer "F.Fab")
		)
		(fp_line
			(start -0.12065 0.3048)
			(end -0.67945 0.3048)
			(stroke
				(width 0.1)
				(type default)
			)
			(layer "F.Fab")
		)
		(fp_line
			(start 0.120396 0.2794)
			(end -0.12065 0.2794)
			(stroke
				(width 0.1)
				(type default)
			)
			(layer "F.Fab")
		)
		(fp_line
			(start 0.120396 0.3048)
			(end 0.120396 0.2794)
			(stroke
				(width 0.1)
				(type default)
			)
			(layer "F.Fab")
		)
		(fp_line
			(start 0.12065 -0.3048)
			(end 0.67945 -0.3048)
			(stroke
				(width 0.1)
				(type default)
			)
			(layer "F.Fab")
		)
		(fp_line
			(start 0.12065 -0.2794)
			(end 0.12065 -0.3048)
			(stroke
				(width 0.1)
				(type default)
			)
			(layer "F.Fab")
		)
		(fp_line
			(start 0.67945 -0.3048)
			(end 0.67945 0.3048)
			(stroke
				(width 0.1)
				(type default)
			)
			(layer "F.Fab")
		)
		(fp_line
			(start 0.67945 0.3048)
			(end 0.120396 0.3048)
			(stroke
				(width 0.1)
				(type default)
			)
			(layer "F.Fab")
		)
		(pad "1" smd circle
			(at -0.40005 0)
			(size 0 0)
			(layers "F.Cu" "F.Mask" "F.Paste")
			(net "P1V25_PEX1_FB")
		)
		(pad "2" smd circle
			(at 0.40005 0)
			(size 0 0)
			(layers "F.Cu" "F.Mask" "F.Paste")
			(net "SH_P1V25_PEX1_FB_P")
		)
	)
)
